(kicad_pcb
	(version 20260206)
	(generator "pcbnew")
	(generator_version "10.0")
	(general
		(thickness 1.6)
		(legacy_teardrops no)
	)
	(paper "A4")
	(title_block
		(title "03242023_DA0F0TMBIJ0_F0T_Motherboard_J_brd_V01_OCP.brd")
		(comment 1 "Grand Teton / footprints 5425-5431 of 6105")
	)
	(layers
		(0 "F.Cu" signal "TOP")
		(4 "In1.Cu" signal "GND")
		(6 "In2.Cu" signal "IN1")
		(8 "In3.Cu" signal "GND1")
		(10 "In4.Cu" signal "IN2")
		(12 "In5.Cu" signal "GND2")
		(14 "In6.Cu" signal "IN3")
		(16 "In7.Cu" signal "GND3")
		(18 "In8.Cu" signal "VCC")
		(20 "In9.Cu" signal "VCC1")
		(22 "In10.Cu" signal "GND4")
		(24 "In11.Cu" signal "IN4")
		(26 "In12.Cu" signal "GND5")
		(28 "In13.Cu" signal "IN5")
		(30 "In14.Cu" signal "GND6")
		(32 "In15.Cu" signal "IN6")
		(34 "In16.Cu" signal "GND7")
		(2 "B.Cu" signal "BOTTOM")
		(9 "F.Adhes" user "F.Adhesive")
		(11 "B.Adhes" user "B.Adhesive")
		(13 "F.Paste" user "Package Geometry/Pastemask Top")
		(15 "B.Paste" user "Package Geometry/Pastemask Bottom")
		(5 "F.SilkS" user "Ref Des/Silkscreen Top")
		(7 "B.SilkS" user "Ref Des/Silkscreen Bottom")
		(1 "F.Mask" user "Board Geometry/Soldermask Top")
		(3 "B.Mask" user "Board Geometry/Soldermask Bottom")
		(17 "Dwgs.User" user "User.Drawings")
		(19 "Cmts.User" user "User.Comments")
		(21 "Eco1.User" user "User.Eco1")
		(23 "Eco2.User" user "User.Eco2")
		(25 "Edge.Cuts" user "Board Geometry/Outline")
		(27 "Margin" user)
		(31 "F.CrtYd" user "Package Geometry/Place Bound Top")
		(29 "B.CrtYd" user "Package Geometry/Place Bound Bottom")
		(35 "F.Fab" user "Ref Des/Assembly Top")
		(33 "B.Fab" user "Ref Des/Assembly Bottom")
	)
	(footprint ""
		(layer "B.Cu")
		(at 36.488624 -407.077164 180)
		(property "Reference" "R5236"
			(at 0 0 0)
			(layer "B.SilkS")
			(hide yes)
			(effects
				(font
					(size 1.27 1.27)
				)
				(justify mirror)
			)
		)
		(property "Value" ""
			(at 0 0 0)
			(layer "B.Fab")
			(effects
				(font
					(size 1.27 1.27)
				)
				(justify mirror)
			)
		)
		(duplicate_pad_numbers_are_jumpers no)
		(fp_line
			(start 0.7874 0.4064)
			(end 0.7874 -0.028956)
			(stroke
				(width 0.1524)
				(type default)
			)
			(layer "B.SilkS")
		)
		(fp_line
			(start 0.529844 -0.4064)
			(end -0.407416 -0.4064)
			(stroke
				(width 0.1524)
				(type default)
			)
			(layer "B.SilkS")
		)
		(fp_line
			(start -0.7874 0.4064)
			(end 0.7874 0.4064)
			(stroke
				(width 0.1524)
				(type default)
			)
			(layer "B.SilkS")
		)
		(fp_line
			(start -0.7874 -0.105156)
			(end -0.7874 0.4064)
			(stroke
				(width 0.1524)
				(type default)
			)
			(layer "B.SilkS")
		)
		(fp_line
			(start 0.67945 0.3048)
			(end 0.67945 -0.305054)
			(stroke
				(width 0.1)
				(type default)
			)
			(layer "B.Fab")
		)
		(fp_line
			(start 0.67945 -0.305054)
			(end 0.12065 -0.305054)
			(stroke
				(width 0.1)
				(type default)
			)
			(layer "B.Fab")
		)
		(fp_line
			(start 0.12065 0.3048)
			(end 0.67945 0.3048)
			(stroke
				(width 0.1)
				(type default)
			)
			(layer "B.Fab")
		)
		(fp_line
			(start 0.12065 0.2794)
			(end 0.12065 0.3048)
			(stroke
				(width 0.1)
				(type default)
			)
			(layer "B.Fab")
		)
		(fp_line
			(start 0.12065 -0.2794)
			(end -0.12065 -0.2794)
			(stroke
				(width 0.1)
				(type default)
			)
			(layer "B.Fab")
		)
		(fp_line
			(start 0.12065 -0.305054)
			(end 0.12065 -0.2794)
			(stroke
				(width 0.1)
				(type default)
			)
			(layer "B.Fab")
		)
		(fp_line
			(start -0.120396 0.3048)
			(end -0.120396 0.2794)
			(stroke
				(width 0.1)
				(type default)
			)
			(layer "B.Fab")
		)
		(fp_line
			(start -0.120396 0.2794)
			(end 0.12065 0.2794)
			(stroke
				(width 0.1)
				(type default)
			)
			(layer "B.Fab")
		)
		(fp_line
			(start -0.12065 -0.2794)
			(end -0.12065 -0.3048)
			(stroke
				(width 0.1)
				(type default)
			)
			(layer "B.Fab")
		)
		(fp_line
			(start -0.12065 -0.3048)
			(end -0.67945 -0.3048)
			(stroke
				(width 0.1)
				(type default)
			)
			(layer "B.Fab")
		)
		(fp_line
			(start -0.67945 0.3048)
			(end -0.120396 0.3048)
			(stroke
				(width 0.1)
				(type default)
			)
			(layer "B.Fab")
		)
		(fp_line
			(start -0.67945 -0.3048)
			(end -0.67945 0.3048)
			(stroke
				(width 0.1)
				(type default)
			)
			(layer "B.Fab")
		)
		(pad "1" smd circle
			(at 0.40005 0)
			(size 0 0)
			(layers "B.Cu" "B.Mask" "B.Paste")
			(net "USB2_HUB_BUF_SWB_R_DN")
		)
		(pad "2" smd circle
			(at -0.40005 0)
			(size 0 0)
			(layers "B.Cu" "B.Mask" "B.Paste")
			(net "USB2_HUB_BUF_SWB_DN")
		)
	)
	(footprint ""
		(layer "B.Cu")
		(at 232.003854 -121.616216 -90)
		(property "Reference" "L4"
			(at 0 0 90)
			(layer "B.SilkS")
			(hide yes)
			(effects
				(font
					(size 1.27 1.27)
				)
				(justify mirror)
			)
		)
		(property "Value" ""
			(at 0 0 90)
			(layer "B.Fab")
			(effects
				(font
					(size 1.27 1.27)
				)
				(justify mirror)
			)
		)
		(duplicate_pad_numbers_are_jumpers no)
		(fp_line
			(start -1.27 0.5842)
			(end 1.27 0.5842)
			(stroke
				(width 0.1524)
				(type default)
			)
			(layer "B.SilkS")
		)
		(fp_line
			(start -1.27 0.5842)
			(end -1.27 -0.5842)
			(stroke
				(width 0.1524)
				(type default)
			)
			(layer "B.SilkS")
		)
		(fp_line
			(start -0.127 0.5842)
			(end -0.127 -0.5842)
			(stroke
				(width 0.1524)
				(type default)
			)
			(layer "B.SilkS")
		)
		(fp_line
			(start 0.127 0.5842)
			(end 0.127 -0.5842)
			(stroke
				(width 0.1524)
				(type default)
			)
			(layer "B.SilkS")
		)
		(fp_line
			(start 1.27 0.5842)
			(end 1.27 -0.5842)
			(stroke
				(width 0.1524)
				(type default)
			)
			(layer "B.SilkS")
		)
		(fp_line
			(start 1.27 -0.5588)
			(end 1.27 -0.5842)
			(stroke
				(width 0.1524)
				(type default)
			)
			(layer "B.SilkS")
		)
		(fp_line
			(start 1.27 -0.5842)
			(end -1.27 -0.5842)
			(stroke
				(width 0.1524)
				(type default)
			)
			(layer "B.SilkS")
		)
		(fp_line
			(start -0.9144 0.508)
			(end 0.9144 0.508)
			(stroke
				(width 0.1)
				(type default)
			)
			(layer "B.Fab")
		)
		(fp_line
			(start 0.9144 0.508)
			(end 0.9144 0.406654)
			(stroke
				(width 0.1)
				(type default)
			)
			(layer "B.Fab")
		)
		(fp_line
			(start 0.9144 0.406654)
			(end 1.194308 0.406654)
			(stroke
				(width 0.1)
				(type default)
			)
			(layer "B.Fab")
		)
		(fp_line
			(start 1.194308 0.406654)
			(end 1.194308 -0.406654)
			(stroke
				(width 0.1)
				(type default)
			)
			(layer "B.Fab")
		)
		(fp_line
			(start -1.1938 0.4064)
			(end -0.9144 0.4064)
			(stroke
				(width 0.1)
				(type default)
			)
			(layer "B.Fab")
		)
		(fp_line
			(start -0.9144 0.4064)
			(end -0.9144 0.508)
			(stroke
				(width 0.1)
				(type default)
			)
			(layer "B.Fab")
		)
		(fp_line
			(start -1.1938 -0.406654)
			(end -1.1938 0.4064)
			(stroke
				(width 0.1)
				(type default)
			)
			(layer "B.Fab")
		)
		(fp_line
			(start -0.9144 -0.406654)
			(end -1.1938 -0.406654)
			(stroke
				(width 0.1)
				(type default)
			)
			(layer "B.Fab")
		)
		(fp_line
			(start 0.9144 -0.406654)
			(end 0.9144 -0.508)
			(stroke
				(width 0.1)
				(type default)
			)
			(layer "B.Fab")
		)
		(fp_line
			(start 1.194308 -0.406654)
			(end 0.9144 -0.406654)
			(stroke
				(width 0.1)
				(type default)
			)
			(layer "B.Fab")
		)
		(fp_line
			(start -0.9144 -0.508)
			(end -0.9144 -0.406654)
			(stroke
				(width 0.1)
				(type default)
			)
			(layer "B.Fab")
		)
		(fp_line
			(start 0.9144 -0.508)
			(end -0.9144 -0.508)
			(stroke
				(width 0.1)
				(type default)
			)
			(layer "B.Fab")
		)
		(pad "1" smd rect
			(at 0.7366 0 180)
			(size 0.7112 0.8128)
			(layers "B.Cu" "B.Mask" "B.Paste")
			(net "P3V3")
		)
		(pad "2" smd rect
			(at -0.7366 0 180)
			(size 0.7112 0.8128)
			(layers "B.Cu" "B.Mask" "B.Paste")
			(net "P3V3_DB2000_FB_VDD")
		)
	)
	(footprint ""
		(layer "B.Cu")
		(at 65.90411 -17.941544)
		(property "Reference" "C1830"
			(at 0 0 0)
			(layer "B.SilkS")
			(hide yes)
			(effects
				(font
					(size 1.27 1.27)
				)
				(justify mirror)
			)
		)
		(property "Value" ""
			(at 0 0 0)
			(layer "B.Fab")
			(effects
				(font
					(size 1.27 1.27)
				)
				(justify mirror)
			)
		)
		(duplicate_pad_numbers_are_jumpers no)
		(fp_line
			(start -1.524 -0.762)
			(end -1.524 0.762)
			(stroke
				(width 0.1524)
				(type default)
			)
			(layer "B.SilkS")
		)
		(fp_line
			(start -1.524 0.762)
			(end 1.524 0.762)
			(stroke
				(width 0.1524)
				(type default)
			)
			(layer "B.SilkS")
		)
		(fp_line
			(start 1.524 -0.762)
			(end -1.524 -0.762)
			(stroke
				(width 0.1524)
				(type default)
			)
			(layer "B.SilkS")
		)
		(fp_line
			(start 1.524 0.762)
			(end 1.524 -0.762)
			(stroke
				(width 0.1524)
				(type default)
			)
			(layer "B.SilkS")
		)
		(fp_line
			(start -1.1049 -0.724916)
			(end 1.1049 -0.724916)
			(stroke
				(width 0.1)
				(type default)
			)
			(layer "B.Fab")
		)
		(fp_line
			(start -1.1049 0.724916)
			(end -1.1049 -0.724916)
			(stroke
				(width 0.1)
				(type default)
			)
			(layer "B.Fab")
		)
		(fp_line
			(start 1.1049 -0.724916)
			(end 1.1049 0.724916)
			(stroke
				(width 0.1)
				(type default)
			)
			(layer "B.Fab")
		)
		(fp_line
			(start 1.1049 0.724916)
			(end -1.1049 0.724916)
			(stroke
				(width 0.1)
				(type default)
			)
			(layer "B.Fab")
		)
		(pad "1" smd rect
			(at 0.889 0)
			(size 1.016 1.27)
			(layers "B.Cu" "B.Mask" "B.Paste")
			(net "P12V_OCP_V3_2")
		)
		(pad "2" smd rect
			(at -0.889 0)
			(size 1.016 1.27)
			(layers "B.Cu" "B.Mask" "B.Paste")
			(net "GND")
		)
	)
	(footprint ""
		(layer "B.Cu")
		(at 34.848546 -321.554856 -90)
		(property "Reference" "C66"
			(at 0 0 90)
			(layer "B.SilkS")
			(hide yes)
			(effects
				(font
					(size 1.27 1.27)
				)
				(justify mirror)
			)
		)
		(property "Value" ""
			(at 0 0 90)
			(layer "B.Fab")
			(effects
				(font
					(size 1.27 1.27)
				)
				(justify mirror)
			)
		)
		(duplicate_pad_numbers_are_jumpers no)
		(fp_line
			(start -1.524 0.762)
			(end 1.524 0.762)
			(stroke
				(width 0.1524)
				(type default)
			)
			(layer "B.SilkS")
		)
		(fp_line
			(start 1.524 0.762)
			(end 1.524 -0.762)
			(stroke
				(width 0.1524)
				(type default)
			)
			(layer "B.SilkS")
		)
		(fp_line
			(start -1.524 -0.762)
			(end -1.524 0.762)
			(stroke
				(width 0.1524)
				(type default)
			)
			(layer "B.SilkS")
		)
		(fp_line
			(start 1.524 -0.762)
			(end -1.524 -0.762)
			(stroke
				(width 0.1524)
				(type default)
			)
			(layer "B.SilkS")
		)
		(fp_line
			(start -1.1049 0.724916)
			(end -1.1049 -0.724916)
			(stroke
				(width 0.1)
				(type default)
			)
			(layer "B.Fab")
		)
		(fp_line
			(start 1.1049 0.724916)
			(end -1.1049 0.724916)
			(stroke
				(width 0.1)
				(type default)
			)
			(layer "B.Fab")
		)
		(fp_line
			(start -1.1049 -0.724916)
			(end 1.1049 -0.724916)
			(stroke
				(width 0.1)
				(type default)
			)
			(layer "B.Fab")
		)
		(fp_line
			(start 1.1049 -0.724916)
			(end 1.1049 0.724916)
			(stroke
				(width 0.1)
				(type default)
			)
			(layer "B.Fab")
		)
		(pad "1" smd rect
			(at 0.889 0 270)
			(size 1.016 1.27)
			(layers "B.Cu" "B.Mask" "B.Paste")
			(net "P12V_S3_AUX_CPU1_NVDIMM")
		)
		(pad "2" smd rect
			(at -0.889 0 270)
			(size 1.016 1.27)
			(layers "B.Cu" "B.Mask" "B.Paste")
			(net "GND")
		)
	)
	(footprint ""
		(layer "B.Cu")
		(at 337.552284 -33.72612 90)
		(property "Reference" "R3325"
			(at 0 0 90)
			(layer "B.SilkS")
			(hide yes)
			(effects
				(font
					(size 1.27 1.27)
				)
				(justify mirror)
			)
		)
		(property "Value" ""
			(at 0 0 90)
			(layer "B.Fab")
			(effects
				(font
					(size 1.27 1.27)
				)
				(justify mirror)
			)
		)
		(duplicate_pad_numbers_are_jumpers no)
		(fp_line
			(start 0.7874 -0.4064)
			(end -0.7874 -0.4064)
			(stroke
				(width 0.1524)
				(type default)
			)
			(layer "B.SilkS")
		)
		(fp_line
			(start -0.7874 -0.4064)
			(end -0.7874 0.4064)
			(stroke
				(width 0.1524)
				(type default)
			)
			(layer "B.SilkS")
		)
		(fp_line
			(start 0.7874 0.4064)
			(end 0.7874 -0.4064)
			(stroke
				(width 0.1524)
				(type default)
			)
			(layer "B.SilkS")
		)
		(fp_line
			(start -0.7874 0.4064)
			(end 0.7874 0.4064)
			(stroke
				(width 0.1524)
				(type default)
			)
			(layer "B.SilkS")
		)
		(fp_line
			(start 0.67945 -0.305054)
			(end 0.12065 -0.305054)
			(stroke
				(width 0.1)
				(type default)
			)
			(layer "B.Fab")
		)
		(fp_line
			(start 0.12065 -0.305054)
			(end 0.12065 -0.2794)
			(stroke
				(width 0.1)
				(type default)
			)
			(layer "B.Fab")
		)
		(fp_line
			(start -0.12065 -0.3048)
			(end -0.67945 -0.3048)
			(stroke
				(width 0.1)
				(type default)
			)
			(layer "B.Fab")
		)
		(fp_line
			(start -0.67945 -0.3048)
			(end -0.67945 0.3048)
			(stroke
				(width 0.1)
				(type default)
			)
			(layer "B.Fab")
		)
		(fp_line
			(start 0.12065 -0.2794)
			(end -0.12065 -0.2794)
			(stroke
				(width 0.1)
				(type default)
			)
			(layer "B.Fab")
		)
		(fp_line
			(start -0.12065 -0.2794)
			(end -0.12065 -0.3048)
			(stroke
				(width 0.1)
				(type default)
			)
			(layer "B.Fab")
		)
		(fp_line
			(start 0.12065 0.2794)
			(end 0.12065 0.3048)
			(stroke
				(width 0.1)
				(type default)
			)
			(layer "B.Fab")
		)
		(fp_line
			(start -0.120396 0.2794)
			(end 0.12065 0.2794)
			(stroke
				(width 0.1)
				(type default)
			)
			(layer "B.Fab")
		)
		(fp_line
			(start 0.67945 0.3048)
			(end 0.67945 -0.305054)
			(stroke
				(width 0.1)
				(type default)
			)
			(layer "B.Fab")
		)
		(fp_line
			(start 0.12065 0.3048)
			(end 0.67945 0.3048)
			(stroke
				(width 0.1)
				(type default)
			)
			(layer "B.Fab")
		)
		(fp_line
			(start -0.120396 0.3048)
			(end -0.120396 0.2794)
			(stroke
				(width 0.1)
				(type default)
			)
			(layer "B.Fab")
		)
		(fp_line
			(start -0.67945 0.3048)
			(end -0.120396 0.3048)
			(stroke
				(width 0.1)
				(type default)
			)
			(layer "B.Fab")
		)
		(pad "1" smd circle
			(at 0.40005 0 270)
			(size 0 0)
			(layers "B.Cu" "B.Mask" "B.Paste")
			(net "FM_PCH_SPKR")
		)
		(pad "2" smd circle
			(at -0.40005 0 270)
			(size 0 0)
			(layers "B.Cu" "B.Mask" "B.Paste")
			(net "GND")
		)
	)
	(footprint ""
		(layer "B.Cu")
		(at 155.38704 -189.34938 -90)
		(property "Reference" "R91"
			(at 0 0 90)
			(layer "B.SilkS")
			(hide yes)
			(effects
				(font
					(size 1.27 1.27)
				)
				(justify mirror)
			)
		)
		(property "Value" ""
			(at 0 0 90)
			(layer "B.Fab")
			(effects
				(font
					(size 1.27 1.27)
				)
				(justify mirror)
			)
		)
		(duplicate_pad_numbers_are_jumpers no)
		(fp_line
			(start -0.7874 0.4064)
			(end 0.7874 0.4064)
			(stroke
				(width 0.1524)
				(type default)
			)
			(layer "B.SilkS")
		)
		(fp_line
			(start 0.7874 0.4064)
			(end 0.7874 -0.4064)
			(stroke
				(width 0.1524)
				(type default)
			)
			(layer "B.SilkS")
		)
		(fp_line
			(start -0.7874 -0.4064)
			(end -0.7874 0.4064)
			(stroke
				(width 0.1524)
				(type default)
			)
			(layer "B.SilkS")
		)
		(fp_line
			(start 0.7874 -0.4064)
			(end -0.7874 -0.4064)
			(stroke
				(width 0.1524)
				(type default)
			)
			(layer "B.SilkS")
		)
		(fp_line
			(start -0.67945 0.3048)
			(end -0.120396 0.3048)
			(stroke
				(width 0.1)
				(type default)
			)
			(layer "B.Fab")
		)
		(fp_line
			(start -0.120396 0.3048)
			(end -0.120396 0.2794)
			(stroke
				(width 0.1)
				(type default)
			)
			(layer "B.Fab")
		)
		(fp_line
			(start 0.12065 0.3048)
			(end 0.67945 0.3048)
			(stroke
				(width 0.1)
				(type default)
			)
			(layer "B.Fab")
		)
		(fp_line
			(start 0.67945 0.3048)
			(end 0.67945 -0.305054)
			(stroke
				(width 0.1)
				(type default)
			)
			(layer "B.Fab")
		)
		(fp_line
			(start -0.120396 0.2794)
			(end 0.12065 0.2794)
			(stroke
				(width 0.1)
				(type default)
			)
			(layer "B.Fab")
		)
		(fp_line
			(start 0.12065 0.2794)
			(end 0.12065 0.3048)
			(stroke
				(width 0.1)
				(type default)
			)
			(layer "B.Fab")
		)
		(fp_line
			(start -0.12065 -0.2794)
			(end -0.12065 -0.3048)
			(stroke
				(width 0.1)
				(type default)
			)
			(layer "B.Fab")
		)
		(fp_line
			(start 0.12065 -0.2794)
			(end -0.12065 -0.2794)
			(stroke
				(width 0.1)
				(type default)
			)
			(layer "B.Fab")
		)
		(fp_line
			(start -0.67945 -0.3048)
			(end -0.67945 0.3048)
			(stroke
				(width 0.1)
				(type default)
			)
			(layer "B.Fab")
		)
		(fp_line
			(start -0.12065 -0.3048)
			(end -0.67945 -0.3048)
			(stroke
				(width 0.1)
				(type default)
			)
			(layer "B.Fab")
		)
		(fp_line
			(start 0.12065 -0.305054)
			(end 0.12065 -0.2794)
			(stroke
				(width 0.1)
				(type default)
			)
			(layer "B.Fab")
		)
		(fp_line
			(start 0.67945 -0.305054)
			(end 0.12065 -0.305054)
			(stroke
				(width 0.1)
				(type default)
			)
			(layer "B.Fab")
		)
		(pad "1" smd circle
			(at 0.40005 0 90)
			(size 0 0)
			(layers "B.Cu" "B.Mask" "B.Paste")
			(net "PVNN_TERM_CPU1")
		)
		(pad "2" smd circle
			(at -0.40005 0 90)
			(size 0 0)
			(layers "B.Cu" "B.Mask" "B.Paste")
			(net "PU_CPU1_UPI1_AC_COUPLING")
		)
	)
	(footprint ""
		(layer "B.Cu")
		(at 278.724614 -319.263776 180)
		(property "Reference" "C17"
			(at 0 0 0)
			(layer "B.SilkS")
			(hide yes)
			(effects
				(font
					(size 1.27 1.27)
				)
				(justify mirror)
			)
		)
		(property "Value" ""
			(at 0 0 0)
			(layer "B.Fab")
			(effects
				(font
					(size 1.27 1.27)
				)
				(justify mirror)
			)
		)
		(duplicate_pad_numbers_are_jumpers no)
		(fp_line
			(start 0.7874 0.4064)
			(end 0.7874 -0.4064)
			(stroke
				(width 0.1524)
				(type default)
			)
			(layer "B.SilkS")
		)
		(fp_line
			(start 0.7874 -0.4064)
			(end -0.7874 -0.4064)
			(stroke
				(width 0.1524)
				(type default)
			)
			(layer "B.SilkS")
		)
		(fp_line
			(start -0.7874 0.4064)
			(end 0.7874 0.4064)
			(stroke
				(width 0.1524)
				(type default)
			)
			(layer "B.SilkS")
		)
		(fp_line
			(start -0.7874 -0.4064)
			(end -0.7874 0.4064)
			(stroke
				(width 0.1524)
				(type default)
			)
			(layer "B.SilkS")
		)
		(fp_line
			(start 0.67945 0.3048)
			(end 0.67945 -0.305054)
			(stroke
				(width 0.1)
				(type default)
			)
			(layer "B.Fab")
		)
		(fp_line
			(start 0.67945 -0.305054)
			(end 0.12065 -0.305054)
			(stroke
				(width 0.1)
				(type default)
			)
			(layer "B.Fab")
		)
		(fp_line
			(start 0.12065 0.3048)
			(end 0.67945 0.3048)
			(stroke
				(width 0.1)
				(type default)
			)
			(layer "B.Fab")
		)
		(fp_line
			(start 0.12065 0.2794)
			(end 0.12065 0.3048)
			(stroke
				(width 0.1)
				(type default)
			)
			(layer "B.Fab")
		)
		(fp_line
			(start 0.12065 -0.2794)
			(end -0.12065 -0.2794)
			(stroke
				(width 0.1)
				(type default)
			)
			(layer "B.Fab")
		)
		(fp_line
			(start 0.12065 -0.305054)
			(end 0.12065 -0.2794)
			(stroke
				(width 0.1)
				(type default)
			)
			(layer "B.Fab")
		)
		(fp_line
			(start -0.120396 0.3048)
			(end -0.120396 0.2794)
			(stroke
				(width 0.1)
				(type default)
			)
			(layer "B.Fab")
		)
		(fp_line
			(start -0.120396 0.2794)
			(end 0.12065 0.2794)
			(stroke
				(width 0.1)
				(type default)
			)
			(layer "B.Fab")
		)
		(fp_line
			(start -0.12065 -0.2794)
			(end -0.12065 -0.3048)
			(stroke
				(width 0.1)
				(type default)
			)
			(layer "B.Fab")
		)
		(fp_line
			(start -0.12065 -0.3048)
			(end -0.67945 -0.3048)
			(stroke
				(width 0.1)
				(type default)
			)
			(layer "B.Fab")
		)
		(fp_line
			(start -0.67945 0.3048)
			(end -0.120396 0.3048)
			(stroke
				(width 0.1)
				(type default)
			)
			(layer "B.Fab")
		)
		(fp_line
			(start -0.67945 -0.3048)
			(end -0.67945 0.3048)
			(stroke
				(width 0.1)
				(type default)
			)
			(layer "B.Fab")
		)
		(pad "1" smd circle
			(at 0.40005 0)
			(size 0 0)
			(layers "B.Cu" "B.Mask" "B.Paste")
			(net "P3V3_AUX")
		)
		(pad "2" smd circle
			(at -0.40005 0)
			(size 0 0)
			(layers "B.Cu" "B.Mask" "B.Paste")
			(net "GND")
		)
	)
)
